(kicad_pcb
	(version 20260206)
	(generator "pcbnew")
	(generator_version "10.0")
	(general
		(thickness 1.6)
		(legacy_teardrops no)
	)
	(paper "A4")
	(title_block
		(title "timecard-production-celestica-r4006 — R4006-B0001-02_R01.brd")
		(comment 1 "Time Appliance Project (Time Card) / footprints 1049-1053 of 1113")
	)
	(layers
		(0 "F.Cu" signal "TOP")
		(4 "In1.Cu" signal "L02_GND1")
		(6 "In2.Cu" signal "L03_SIG1")
		(8 "In3.Cu" signal "L04_GND2")
		(10 "In4.Cu" signal "L05_VCC1")
		(12 "In5.Cu" signal "L06_VCC2")
		(14 "In6.Cu" signal "L07_GND3")
		(16 "In7.Cu" signal "L08_SIG2")
		(18 "In8.Cu" signal "L09_GND4")
		(2 "B.Cu" signal "BOTTOM")
		(9 "F.Adhes" user "F.Adhesive")
		(11 "B.Adhes" user "B.Adhesive")
		(13 "F.Paste" user "Package Geometry/Pastemask Top")
		(15 "B.Paste" user "Package Geometry/Pastemask Bottom")
		(5 "F.SilkS" user "Ref Des/Silkscreen Top")
		(7 "B.SilkS" user "Ref Des/Silkscreen Bottom")
		(1 "F.Mask" user "Board Geometry/Soldermask Top")
		(3 "B.Mask" user "Board Geometry/Soldermask Bottom")
		(17 "Dwgs.User" user "User.Drawings")
		(19 "Cmts.User" user "User.Comments")
		(21 "Eco1.User" user "User.Eco1")
		(23 "Eco2.User" user "User.Eco2")
		(25 "Edge.Cuts" user "Board Geometry/Outline")
		(27 "Margin" user)
		(31 "F.CrtYd" user "Package Geometry/Place Bound Top")
		(29 "B.CrtYd" user "Package Geometry/Place Bound Bottom")
		(35 "F.Fab" user "Ref Des/Assembly Top")
		(33 "B.Fab" user "Ref Des/Assembly Bottom")
	)
	(footprint ""
		(layer "B.Cu")
		(at 83.2358 -87.122 180)
		(property "Reference" "R155"
			(at 0.6858 5.42163 0)
			(unlocked yes)
			(layer "B.SilkS")
			(effects
				(font
					(size 0.7874 0.5842)
					(thickness 0.1524)
				)
				(justify mirror)
			)
		)
		(property "Value" "VAL*"
			(at -0.02032 2.13233 180)
			(unlocked yes)
			(layer "B.Fab")
			(hide yes)
			(effects
				(font
					(size 0.7874 0.5842)
					(thickness 0.1524)
				)
				(justify mirror)
			)
		)
		(property "Tolerance" "TOL*"
			(at -0.044704 3.05435 180)
			(unlocked yes)
			(layer "Cmts.User")
			(hide yes)
			(effects
				(font
					(size 0.7874 0.5842)
					(thickness 0.1524)
				)
				(justify mirror)
			)
		)
		(property "User Part Number" "PARTNUM*"
			(at -0.02032 4.024884 180)
			(unlocked yes)
			(layer "Cmts.User")
			(hide yes)
			(effects
				(font
					(size 0.7874 0.5842)
					(thickness 0.1524)
				)
				(justify mirror)
			)
		)
		(property "Device Type" "RESISTOR-G155-14701-01,4.7KOHMA"
			(at -0.008382 1.210564 180)
			(unlocked yes)
			(layer "B.Fab")
			(hide yes)
			(effects
				(font
					(size 0.7874 0.5842)
					(thickness 0.1524)
				)
				(justify mirror)
			)
		)
		(duplicate_pad_numbers_are_jumpers no)
		(fp_line
			(start 1.143 0.5588)
			(end -1.143 0.5588)
			(stroke
				(width 0.1)
				(type default)
			)
			(layer "B.SilkS")
		)
		(fp_line
			(start 1.143 -0.5588)
			(end 1.143 0.5588)
			(stroke
				(width 0.1)
				(type default)
			)
			(layer "B.SilkS")
		)
		(fp_line
			(start -1.143 0.5588)
			(end -1.143 -0.5588)
			(stroke
				(width 0.1)
				(type default)
			)
			(layer "B.SilkS")
		)
		(fp_line
			(start -1.143 -0.5588)
			(end 1.143 -0.5588)
			(stroke
				(width 0.1)
				(type default)
			)
			(layer "B.SilkS")
		)
		(fp_rect
			(start -1.143 0.5588)
			(end 1.143 -0.5588)
			(stroke
				(width 0)
				(type default)
			)
			(fill no)
			(layer "B.CrtYd")
		)
		(fp_line
			(start 0.508 0.3048)
			(end -0.508 0.3048)
			(stroke
				(width 0.1)
				(type default)
			)
			(layer "B.Fab")
		)
		(fp_line
			(start 0.508 -0.3048)
			(end 0.508 0.3048)
			(stroke
				(width 0.1)
				(type default)
			)
			(layer "B.Fab")
		)
		(fp_line
			(start -0.508 0.3048)
			(end -0.508 -0.3048)
			(stroke
				(width 0.1)
				(type default)
			)
			(layer "B.Fab")
		)
		(fp_line
			(start -0.508 -0.3048)
			(end 0.508 -0.3048)
			(stroke
				(width 0.1)
				(type default)
			)
			(layer "B.Fab")
		)
		(pad "1" smd rect
			(at 0.5334 0)
			(size 0.7112 0.6096)
			(layers "B.Cu" "B.Mask" "B.Paste")
			(net "SG")
		)
		(pad "2" smd rect
			(at -0.5334 0)
			(size 0.7112 0.6096)
			(layers "B.Cu" "B.Mask" "B.Paste")
			(net "PCA9546_RST_N")
		)
		(zone
			(layer "B.Cu")
			(hatch none 0.5)
			(connect_pads
				(clearance 0)
			)
			(min_thickness 0.25)
			(keepout
				(tracks allowed)
				(vias not_allowed)
				(pads allowed)
				(copperpour not_allowed)
				(footprints allowed)
			)
			(placement
				(enabled no)
				(sheetname "")
			)
			(fill
				(thermal_gap 0.5)
				(thermal_bridge_width 0.5)
				(island_removal_mode 0)
			)
			(polygon
				(pts
					(xy 83.312 -87.4268) (xy 83.1596 -87.4268) (xy 83.1596 -86.8172) (xy 83.312 -86.8172)
				)
			)
		)
	)
	(footprint ""
		(layer "B.Cu")
		(at 105.847134 -42.323258 -90)
		(property "Reference" "C156"
			(at 1.015238 41.383204 270)
			(unlocked yes)
			(layer "B.SilkS")
			(effects
				(font
					(size 0.635 0.4064)
					(thickness 0.1524)
				)
				(justify mirror)
			)
		)
		(property "Value" "VAL*"
			(at 0 3.718306 270)
			(unlocked yes)
			(layer "B.Fab")
			(hide yes)
			(effects
				(font
					(size 0.7874 0.5842)
					(thickness 0.127)
				)
				(justify mirror)
			)
		)
		(property "Device Type" "CAPACITOR-G105-0B104-CK,0.1UF,A"
			(at 0 1.432306 270)
			(unlocked yes)
			(layer "B.Fab")
			(hide yes)
			(effects
				(font
					(size 0.7874 0.5842)
					(thickness 0.127)
				)
				(justify mirror)
			)
		)
		(property "User Part Number" "PARTNUM*"
			(at 0 2.575306 270)
			(unlocked yes)
			(layer "Cmts.User")
			(hide yes)
			(effects
				(font
					(size 0.7874 0.5842)
					(thickness 0.127)
				)
				(justify mirror)
			)
		)
		(property "Tolerance" "TOL*"
			(at 0 4.861306 270)
			(unlocked yes)
			(layer "Cmts.User")
			(hide yes)
			(effects
				(font
					(size 0.7874 0.5842)
					(thickness 0.127)
				)
				(justify mirror)
			)
		)
		(duplicate_pad_numbers_are_jumpers no)
		(fp_line
			(start -0.970026 0.4699)
			(end 0.970026 0.4699)
			(stroke
				(width 0.1)
				(type default)
			)
			(layer "B.SilkS")
		)
		(fp_line
			(start 0.970026 0.4699)
			(end 0.970026 -0.4699)
			(stroke
				(width 0.1)
				(type default)
			)
			(layer "B.SilkS")
		)
		(fp_line
			(start -0.970026 -0.4699)
			(end -0.970026 0.4699)
			(stroke
				(width 0.1)
				(type default)
			)
			(layer "B.SilkS")
		)
		(fp_line
			(start 0.970026 -0.4699)
			(end -0.970026 -0.4699)
			(stroke
				(width 0.1)
				(type default)
			)
			(layer "B.SilkS")
		)
		(fp_poly
			(pts
				(xy 0.970026 0.4699) (xy -0.970026 0.4699) (xy -0.970026 -0.4699) (xy 0.970026 -0.4699)
			)
			(stroke
				(width 0)
				(type default)
			)
			(fill no)
			(layer "B.CrtYd")
		)
		(fp_line
			(start -0.508 0.3048)
			(end 0.508 0.3048)
			(stroke
				(width 0.1)
				(type default)
			)
			(layer "B.Fab")
		)
		(fp_line
			(start 0.508 0.3048)
			(end 0.508 -0.3048)
			(stroke
				(width 0.1)
				(type default)
			)
			(layer "B.Fab")
		)
		(fp_line
			(start -0.508 -0.3048)
			(end -0.508 0.3048)
			(stroke
				(width 0.1)
				(type default)
			)
			(layer "B.Fab")
		)
		(fp_line
			(start 0.508 -0.3048)
			(end -0.508 -0.3048)
			(stroke
				(width 0.1)
				(type default)
			)
			(layer "B.Fab")
		)
		(pad "1" smd circle
			(at 0.500126 0 90)
			(size 0.635 0.635)
			(layers "B.Cu" "B.Mask" "B.Paste")
			(net "XP1R0V_FPGA_VCCINT")
		)
		(pad "2" smd circle
			(at -0.500126 0 90)
			(size 0.635 0.635)
			(layers "B.Cu" "B.Mask" "B.Paste")
			(net "SG")
		)
	)
	(footprint ""
		(layer "B.Cu")
		(at 53.975 -90.17)
		(property "Reference" "R446"
			(at 0.127 -4.15163 0)
			(unlocked yes)
			(layer "B.SilkS")
			(effects
				(font
					(size 0.7874 0.5842)
					(thickness 0.1524)
				)
				(justify mirror)
			)
		)
		(property "Value" "VAL*"
			(at -0.02032 2.13233 0)
			(unlocked yes)
			(layer "B.Fab")
			(hide yes)
			(effects
				(font
					(size 0.7874 0.5842)
					(thickness 0.1524)
				)
				(justify mirror)
			)
		)
		(property "Tolerance" "TOL*"
			(at -0.044704 3.05435 0)
			(unlocked yes)
			(layer "Cmts.User")
			(hide yes)
			(effects
				(font
					(size 0.7874 0.5842)
					(thickness 0.1524)
				)
				(justify mirror)
			)
		)
		(property "User Part Number" "PARTNUM*"
			(at -0.02032 4.024884 0)
			(unlocked yes)
			(layer "Cmts.User")
			(hide yes)
			(effects
				(font
					(size 0.7874 0.5842)
					(thickness 0.1524)
				)
				(justify mirror)
			)
		)
		(property "Device Type" "RESISTOR-G155-11002-01,10KOHM,A"
			(at -0.008382 1.210564 0)
			(unlocked yes)
			(layer "B.Fab")
			(hide yes)
			(effects
				(font
					(size 0.7874 0.5842)
					(thickness 0.1524)
				)
				(justify mirror)
			)
		)
		(duplicate_pad_numbers_are_jumpers no)
		(fp_line
			(start -1.143 -0.5588)
			(end 1.143 -0.5588)
			(stroke
				(width 0.1)
				(type default)
			)
			(layer "B.SilkS")
		)
		(fp_line
			(start -1.143 0.5588)
			(end -1.143 -0.5588)
			(stroke
				(width 0.1)
				(type default)
			)
			(layer "B.SilkS")
		)
		(fp_line
			(start 1.143 -0.5588)
			(end 1.143 0.5588)
			(stroke
				(width 0.1)
				(type default)
			)
			(layer "B.SilkS")
		)
		(fp_line
			(start 1.143 0.5588)
			(end -1.143 0.5588)
			(stroke
				(width 0.1)
				(type default)
			)
			(layer "B.SilkS")
		)
		(fp_poly
			(pts
				(xy 1.143 0.5588) (xy -1.143 0.5588) (xy -1.143 -0.5588) (xy 1.143 -0.5588)
			)
			(stroke
				(width 0)
				(type default)
			)
			(fill no)
			(layer "B.CrtYd")
		)
		(fp_line
			(start -0.508 -0.3048)
			(end 0.508 -0.3048)
			(stroke
				(width 0.1)
				(type default)
			)
			(layer "B.Fab")
		)
		(fp_line
			(start -0.508 0.3048)
			(end -0.508 -0.3048)
			(stroke
				(width 0.1)
				(type default)
			)
			(layer "B.Fab")
		)
		(fp_line
			(start 0.508 -0.3048)
			(end 0.508 0.3048)
			(stroke
				(width 0.1)
				(type default)
			)
			(layer "B.Fab")
		)
		(fp_line
			(start 0.508 0.3048)
			(end -0.508 0.3048)
			(stroke
				(width 0.1)
				(type default)
			)
			(layer "B.Fab")
		)
		(pad "1" smd rect
			(at 0.5334 0 180)
			(size 0.7112 0.6096)
			(layers "B.Cu" "B.Mask" "B.Paste")
			(net "XP3R3V_FT4232")
		)
		(pad "2" smd rect
			(at -0.5334 0 180)
			(size 0.7112 0.6096)
			(layers "B.Cu" "B.Mask" "B.Paste")
			(net "FTDI_EE_CS")
		)
		(zone
			(layer "B.Cu")
			(hatch none 0.5)
			(connect_pads
				(clearance 0)
			)
			(min_thickness 0.25)
			(keepout
				(tracks not_allowed)
				(vias allowed)
				(pads allowed)
				(copperpour not_allowed)
				(footprints allowed)
			)
			(placement
				(enabled no)
				(sheetname "")
			)
			(fill
				(thermal_gap 0.5)
				(thermal_bridge_width 0.5)
				(island_removal_mode 0)
			)
			(polygon
				(pts
					(xy 54.0512 -89.8652) (xy 54.0512 -90.4748) (xy 53.8988 -90.4748) (xy 53.8988 -89.8652)
				)
			)
		)
		(zone
			(layer "B.Cu")
			(hatch none 0.5)
			(connect_pads
				(clearance 0)
			)
			(min_thickness 0.25)
			(keepout
				(tracks allowed)
				(vias not_allowed)
				(pads allowed)
				(copperpour not_allowed)
				(footprints allowed)
			)
			(placement
				(enabled no)
				(sheetname "")
			)
			(fill
				(thermal_gap 0.5)
				(thermal_bridge_width 0.5)
				(island_removal_mode 0)
			)
			(polygon
				(pts
					(xy 54.0512 -89.8652) (xy 54.0512 -90.4748) (xy 53.8988 -90.4748) (xy 53.8988 -89.8652)
				)
			)
		)
	)
	(footprint ""
		(layer "B.Cu")
		(at 146.6088 -17.2466 90)
		(property "Reference" "R227"
			(at -0.3556 1.81483 270)
			(unlocked yes)
			(layer "B.SilkS")
			(effects
				(font
					(size 0.7874 0.5842)
					(thickness 0.1524)
				)
				(justify mirror)
			)
		)
		(property "Value" "VAL*"
			(at -0.02032 2.13233 90)
			(unlocked yes)
			(layer "B.Fab")
			(hide yes)
			(effects
				(font
					(size 0.7874 0.5842)
					(thickness 0.1524)
				)
				(justify mirror)
			)
		)
		(property "Tolerance" "TOL*"
			(at -0.044704 3.05435 90)
			(unlocked yes)
			(layer "Cmts.User")
			(hide yes)
			(effects
				(font
					(size 0.7874 0.5842)
					(thickness 0.1524)
				)
				(justify mirror)
			)
		)
		(property "User Part Number" "PARTNUM*"
			(at -0.02032 4.024884 90)
			(unlocked yes)
			(layer "Cmts.User")
			(hide yes)
			(effects
				(font
					(size 0.7874 0.5842)
					(thickness 0.1524)
				)
				(justify mirror)
			)
		)
		(property "Device Type" "RESISTOR-G155-11002-01,10KOHM,A"
			(at -0.008382 1.210564 90)
			(unlocked yes)
			(layer "B.Fab")
			(hide yes)
			(effects
				(font
					(size 0.7874 0.5842)
					(thickness 0.1524)
				)
				(justify mirror)
			)
		)
		(duplicate_pad_numbers_are_jumpers no)
		(fp_line
			(start 1.143 -0.5588)
			(end 1.143 0.5588)
			(stroke
				(width 0.1)
				(type default)
			)
			(layer "B.SilkS")
		)
		(fp_line
			(start -1.143 -0.5588)
			(end 1.143 -0.5588)
			(stroke
				(width 0.1)
				(type default)
			)
			(layer "B.SilkS")
		)
		(fp_line
			(start 1.143 0.5588)
			(end -1.143 0.5588)
			(stroke
				(width 0.1)
				(type default)
			)
			(layer "B.SilkS")
		)
		(fp_line
			(start -1.143 0.5588)
			(end -1.143 -0.5588)
			(stroke
				(width 0.1)
				(type default)
			)
			(layer "B.SilkS")
		)
		(fp_rect
			(start 1.143 0.5588)
			(end -1.143 -0.5588)
			(stroke
				(width 0)
				(type default)
			)
			(fill no)
			(layer "B.CrtYd")
		)
		(fp_line
			(start 0.508 -0.3048)
			(end 0.508 0.3048)
			(stroke
				(width 0.1)
				(type default)
			)
			(layer "B.Fab")
		)
		(fp_line
			(start -0.508 -0.3048)
			(end 0.508 -0.3048)
			(stroke
				(width 0.1)
				(type default)
			)
			(layer "B.Fab")
		)
		(fp_line
			(start 0.508 0.3048)
			(end -0.508 0.3048)
			(stroke
				(width 0.1)
				(type default)
			)
			(layer "B.Fab")
		)
		(fp_line
			(start -0.508 0.3048)
			(end -0.508 -0.3048)
			(stroke
				(width 0.1)
				(type default)
			)
			(layer "B.Fab")
		)
		(pad "1" smd rect
			(at 0.5334 0 270)
			(size 0.7112 0.6096)
			(layers "B.Cu" "B.Mask" "B.Paste")
			(net "UNNAMED_515_CAPACITOR_I128_1")
		)
		(pad "2" smd rect
			(at -0.5334 0 270)
			(size 0.7112 0.6096)
			(layers "B.Cu" "B.Mask" "B.Paste")
			(net "SG")
		)
		(zone
			(layer "B.Cu")
			(hatch none 0.5)
			(connect_pads
				(clearance 0)
			)
			(min_thickness 0.25)
			(keepout
				(tracks allowed)
				(vias not_allowed)
				(pads allowed)
				(copperpour not_allowed)
				(footprints allowed)
			)
			(placement
				(enabled no)
				(sheetname "")
			)
			(fill
				(thermal_gap 0.5)
				(thermal_bridge_width 0.5)
				(island_removal_mode 0)
			)
			(polygon
				(pts
					(xy 146.9136 -17.3228) (xy 146.304 -17.3228) (xy 146.304 -17.1704) (xy 146.9136 -17.1704)
				)
			)
		)
	)
	(footprint ""
		(layer "B.Cu")
		(at 20.2946 -18.5928 90)
		(property "Reference" "R2"
			(at -0.1778 -1.15697 270)
			(unlocked yes)
			(layer "B.SilkS")
			(effects
				(font
					(size 0.7874 0.5842)
					(thickness 0.1524)
				)
				(justify mirror)
			)
		)
		(property "Value" "VAL*"
			(at -0.02032 2.13233 90)
			(unlocked yes)
			(layer "B.Fab")
			(hide yes)
			(effects
				(font
					(size 0.7874 0.5842)
					(thickness 0.1524)
				)
				(justify mirror)
			)
		)
		(property "Device Type" "RESISTOR-G155-13300-01,330OHM,A"
			(at -0.008382 1.210564 90)
			(unlocked yes)
			(layer "B.Fab")
			(hide yes)
			(effects
				(font
					(size 0.7874 0.5842)
					(thickness 0.1524)
				)
				(justify mirror)
			)
		)
		(property "User Part Number" "PARTNUM*"
			(at -0.02032 4.024884 90)
			(unlocked yes)
			(layer "Cmts.User")
			(hide yes)
			(effects
				(font
					(size 0.7874 0.5842)
					(thickness 0.1524)
				)
				(justify mirror)
			)
		)
		(property "Tolerance" "TOL*"
			(at -0.044704 3.05435 90)
			(unlocked yes)
			(layer "Cmts.User")
			(hide yes)
			(effects
				(font
					(size 0.7874 0.5842)
					(thickness 0.1524)
				)
				(justify mirror)
			)
		)
		(duplicate_pad_numbers_are_jumpers no)
		(fp_line
			(start 1.143 -0.5588)
			(end 1.143 0.5588)
			(stroke
				(width 0.1)
				(type default)
			)
			(layer "B.SilkS")
		)
		(fp_line
			(start -1.143 -0.5588)
			(end 1.143 -0.5588)
			(stroke
				(width 0.1)
				(type default)
			)
			(layer "B.SilkS")
		)
		(fp_line
			(start 1.143 0.5588)
			(end -1.143 0.5588)
			(stroke
				(width 0.1)
				(type default)
			)
			(layer "B.SilkS")
		)
		(fp_line
			(start -1.143 0.5588)
			(end -1.143 -0.5588)
			(stroke
				(width 0.1)
				(type default)
			)
			(layer "B.SilkS")
		)
		(fp_rect
			(start 1.143 -0.5588)
			(end -1.143 0.5588)
			(stroke
				(width 0)
				(type default)
			)
			(fill no)
			(layer "B.CrtYd")
		)
		(fp_line
			(start 0.508 -0.3048)
			(end 0.508 0.3048)
			(stroke
				(width 0.1)
				(type default)
			)
			(layer "B.Fab")
		)
		(fp_line
			(start -0.508 -0.3048)
			(end 0.508 -0.3048)
			(stroke
				(width 0.1)
				(type default)
			)
			(layer "B.Fab")
		)
		(fp_line
			(start 0.508 0.3048)
			(end -0.508 0.3048)
			(stroke
				(width 0.1)
				(type default)
			)
			(layer "B.Fab")
		)
		(fp_line
			(start -0.508 0.3048)
			(end -0.508 -0.3048)
			(stroke
				(width 0.1)
				(type default)
			)
			(layer "B.Fab")
		)
		(pad "1" smd rect
			(at 0.5334 0 270)
			(size 0.7112 0.6096)
			(layers "B.Cu" "B.Mask" "B.Paste")
			(net "FPGA_OUT_SEC_EEPROM_WP")
		)
		(pad "2" smd rect
			(at -0.5334 0 270)
			(size 0.7112 0.6096)
			(layers "B.Cu" "B.Mask" "B.Paste")
			(net "SEC_EEPROM_WP")
		)
		(zone
			(layer "B.Cu")
			(hatch none 0.5)
			(connect_pads
				(clearance 0)
			)
			(min_thickness 0.25)
			(keepout
				(tracks allowed)
				(vias not_allowed)
				(pads allowed)
				(copperpour not_allowed)
				(footprints allowed)
			)
			(placement
				(enabled no)
				(sheetname "")
			)
			(fill
				(thermal_gap 0.5)
				(thermal_bridge_width 0.5)
				(island_removal_mode 0)
			)
			(polygon
				(pts
					(xy 19.9898 -18.669) (xy 19.9898 -18.5166) (xy 20.5994 -18.5166) (xy 20.5994 -18.669)
				)
			)
		)
	)
)
